(kicad_pcb
	(version 20260206)
	(generator "pcbnew")
	(generator_version "10.0")
	(general
		(thickness 1.6)
		(legacy_teardrops no)
	)
	(paper "A4")
	(title_block
		(title "panther-plus-userver — 13130-1b_20150205.brd")
		(comment 1 "Honey Badger (Wiwynn) / footprints 774-781 of 1509")
	)
	(layers
		(0 "F.Cu" signal "TOP")
		(4 "In1.Cu" signal "L2")
		(6 "In2.Cu" signal "L3")
		(8 "In3.Cu" signal "L4")
		(10 "In4.Cu" signal "L5")
		(12 "In5.Cu" signal "L6")
		(14 "In6.Cu" signal "L7")
		(16 "In7.Cu" signal "L8")
		(18 "In8.Cu" signal "L9")
		(20 "In9.Cu" signal "L10")
		(22 "In10.Cu" signal "L11")
		(2 "B.Cu" signal "BOTTOM")
		(9 "F.Adhes" user "F.Adhesive")
		(11 "B.Adhes" user "B.Adhesive")
		(13 "F.Paste" user "Package Geometry/Pastemask Top")
		(15 "B.Paste" user "Package Geometry/Pastemask Bottom")
		(5 "F.SilkS" user "Ref Des/Silkscreen Top")
		(7 "B.SilkS" user "Ref Des/Silkscreen Bottom")
		(1 "F.Mask" user "Board Geometry/Soldermask Top")
		(3 "B.Mask" user "Board Geometry/Soldermask Bottom")
		(17 "Dwgs.User" user "User.Drawings")
		(19 "Cmts.User" user "User.Comments")
		(21 "Eco1.User" user "User.Eco1")
		(23 "Eco2.User" user "User.Eco2")
		(25 "Edge.Cuts" user "Board Geometry/Outline")
		(27 "Margin" user)
		(31 "F.CrtYd" user "Package Geometry/Place Bound Top")
		(29 "B.CrtYd" user "Package Geometry/Place Bound Bottom")
		(35 "F.Fab" user "Ref Des/Assembly Top")
		(33 "B.Fab" user "Ref Des/Assembly Bottom")
	)
	(footprint ""
		(layer "F.Cu")
		(at 15.5702 -63.9064 180)
		(property "Reference" "PR37"
			(at 0 0 180)
			(layer "F.SilkS")
			(hide yes)
			(effects
				(font
					(size 1.27 1.27)
				)
			)
		)
		(property "Value" "0R2J-2-GP"
			(at 1.7907 -1.1176 180)
			(unlocked yes)
			(layer "F.Fab")
			(hide yes)
			(effects
				(font
					(size 1.016 1.016)
					(thickness 0.1524)
				)
			)
		)
		(property "Device Type" "R402H16"
			(at 1.7907 -2.6416 180)
			(unlocked yes)
			(layer "F.Fab")
			(hide yes)
			(effects
				(font
					(size 1.016 1.016)
					(thickness 0.1524)
				)
			)
		)
		(duplicate_pad_numbers_are_jumpers no)
		(fp_rect
			(start -0.381 0.8382)
			(end 0.381 -0.8382)
			(stroke
				(width 0)
				(type default)
			)
			(fill no)
			(layer "F.CrtYd")
		)
		(fp_rect
			(start -0.381 0.8382)
			(end 0.381 -0.8382)
			(stroke
				(width 0)
				(type default)
			)
			(fill no)
			(layer "F.Fab")
		)
		(pad "1" smd custom
			(at 0 -0.4318 180)
			(size 0.127 0.127)
			(layers "F.Cu" "F.Mask" "F.Paste")
			(net "PWRGD_R_PVNN")
			(options
				(clearance outline)
				(anchor circle)
			)
			(primitives
				(gr_poly
					(pts
						(arc
							(start -0.2032 -0.2794)
							(mid -0.239121 -0.264521)
							(end -0.254 -0.2286)
						)
						(arc
							(start -0.254 0.2286)
							(mid -0.239121 0.264521)
							(end -0.2032 0.2794)
						)
						(arc
							(start 0.2032 0.2794)
							(mid 0.239121 0.264521)
							(end 0.254 0.2286)
						)
						(arc
							(start 0.254 -0.2286)
							(mid 0.239121 -0.264521)
							(end 0.2032 -0.2794)
						)
					)
					(width 0)
					(fill yes)
				)
			)
		)
		(pad "2" smd custom
			(at 0 0.4318 180)
			(size 0.127 0.127)
			(layers "F.Cu" "F.Mask" "F.Paste")
			(net "PWRGD_PVCCP_VNN_PG")
			(options
				(clearance outline)
				(anchor circle)
			)
			(primitives
				(gr_poly
					(pts
						(arc
							(start -0.2032 -0.2794)
							(mid -0.239121 -0.264521)
							(end -0.254 -0.2286)
						)
						(arc
							(start -0.254 0.2286)
							(mid -0.239121 0.264521)
							(end -0.2032 0.2794)
						)
						(arc
							(start 0.2032 0.2794)
							(mid 0.239121 0.264521)
							(end 0.254 0.2286)
						)
						(arc
							(start 0.254 -0.2286)
							(mid 0.239121 -0.264521)
							(end 0.2032 -0.2794)
						)
					)
					(width 0)
					(fill yes)
				)
			)
		)
	)
	(footprint ""
		(layer "F.Cu")
		(at 154.94 -24.384 90)
		(property "Reference" "C74"
			(at 0 0 90)
			(layer "F.SilkS")
			(hide yes)
			(effects
				(font
					(size 1.27 1.27)
				)
			)
		)
		(property "Value" "SCD1U10V2KX-5GP"
			(at 1.1811 -2.7051 90)
			(unlocked yes)
			(layer "F.Fab")
			(hide yes)
			(effects
				(font
					(size 1.016 1.016)
					(thickness 0.1524)
				)
			)
		)
		(property "Device Type" "C402H22"
			(at 1.1811 -4.2291 90)
			(unlocked yes)
			(layer "F.Fab")
			(hide yes)
			(effects
				(font
					(size 1.016 1.016)
					(thickness 0.1524)
				)
			)
		)
		(duplicate_pad_numbers_are_jumpers no)
		(fp_rect
			(start -0.381 0.7366)
			(end 0.381 -0.7366)
			(stroke
				(width 0)
				(type default)
			)
			(fill no)
			(layer "F.CrtYd")
		)
		(fp_rect
			(start -0.381 0.7366)
			(end 0.381 -0.7366)
			(stroke
				(width 0)
				(type default)
			)
			(fill no)
			(layer "F.Fab")
		)
		(pad "1" smd custom
			(at 0 -0.4572 90)
			(size 0.1143 0.1143)
			(layers "F.Cu" "F.Mask" "F.Paste")
			(net "P1V2_FPGA_A")
			(options
				(clearance outline)
				(anchor circle)
			)
			(primitives
				(gr_poly
					(pts
						(arc
							(start -0.254 -0.1778)
							(mid -0.239121 -0.213721)
							(end -0.2032 -0.2286)
						)
						(arc
							(start 0.2032 -0.2286)
							(mid 0.239121 -0.213721)
							(end 0.254 -0.1778)
						)
						(arc
							(start 0.254 0.1778)
							(mid 0.239121 0.213721)
							(end 0.2032 0.2286)
						)
						(arc
							(start -0.2032 0.2286)
							(mid -0.239121 0.213721)
							(end -0.254 0.1778)
						)
					)
					(width 0)
					(fill yes)
				)
			)
		)
		(pad "2" smd custom
			(at 0 0.4572 90)
			(size 0.1143 0.1143)
			(layers "F.Cu" "F.Mask" "F.Paste")
			(net "GND")
			(options
				(clearance outline)
				(anchor circle)
			)
			(primitives
				(gr_poly
					(pts
						(arc
							(start -0.254 -0.1778)
							(mid -0.239121 -0.213721)
							(end -0.2032 -0.2286)
						)
						(arc
							(start 0.2032 -0.2286)
							(mid 0.239121 -0.213721)
							(end 0.254 -0.1778)
						)
						(arc
							(start 0.254 0.1778)
							(mid 0.239121 0.213721)
							(end 0.2032 0.2286)
						)
						(arc
							(start -0.2032 0.2286)
							(mid -0.239121 0.213721)
							(end -0.254 0.1778)
						)
					)
					(width 0)
					(fill yes)
				)
			)
		)
	)
	(footprint ""
		(layer "F.Cu")
		(at 184.2008 -30.0228 180)
		(property "Reference" "PR156"
			(at 0 0 180)
			(layer "F.SilkS")
			(hide yes)
			(effects
				(font
					(size 1.27 1.27)
				)
			)
		)
		(property "Value" "3K3R2F-2-GP"
			(at 1.7907 -1.1176 180)
			(unlocked yes)
			(layer "F.Fab")
			(hide yes)
			(effects
				(font
					(size 1.016 1.016)
					(thickness 0.1524)
				)
			)
		)
		(property "Device Type" "R402H16"
			(at 1.7907 -2.6416 180)
			(unlocked yes)
			(layer "F.Fab")
			(hide yes)
			(effects
				(font
					(size 1.016 1.016)
					(thickness 0.1524)
				)
			)
		)
		(duplicate_pad_numbers_are_jumpers no)
		(fp_rect
			(start -0.381 0.8382)
			(end 0.381 -0.8382)
			(stroke
				(width 0)
				(type default)
			)
			(fill no)
			(layer "F.CrtYd")
		)
		(fp_rect
			(start -0.381 0.8382)
			(end 0.381 -0.8382)
			(stroke
				(width 0)
				(type default)
			)
			(fill no)
			(layer "F.Fab")
		)
		(pad "1" smd custom
			(at 0 -0.4318 180)
			(size 0.127 0.127)
			(layers "F.Cu" "F.Mask" "F.Paste")
			(net "VR_PVDDR_A_FB_COMP")
			(options
				(clearance outline)
				(anchor circle)
			)
			(primitives
				(gr_poly
					(pts
						(arc
							(start -0.2032 -0.2794)
							(mid -0.239121 -0.264521)
							(end -0.254 -0.2286)
						)
						(arc
							(start -0.254 0.2286)
							(mid -0.239121 0.264521)
							(end -0.2032 0.2794)
						)
						(arc
							(start 0.2032 0.2794)
							(mid 0.239121 0.264521)
							(end 0.254 0.2286)
						)
						(arc
							(start 0.254 -0.2286)
							(mid 0.239121 -0.264521)
							(end 0.2032 -0.2794)
						)
					)
					(width 0)
					(fill yes)
				)
			)
		)
		(pad "2" smd custom
			(at 0 0.4318 180)
			(size 0.127 0.127)
			(layers "F.Cu" "F.Mask" "F.Paste")
			(net "VR_PVDDR_A_FB")
			(options
				(clearance outline)
				(anchor circle)
			)
			(primitives
				(gr_poly
					(pts
						(arc
							(start -0.2032 -0.2794)
							(mid -0.239121 -0.264521)
							(end -0.254 -0.2286)
						)
						(arc
							(start -0.254 0.2286)
							(mid -0.239121 0.264521)
							(end -0.2032 0.2794)
						)
						(arc
							(start 0.2032 0.2794)
							(mid 0.239121 0.264521)
							(end 0.254 0.2286)
						)
						(arc
							(start 0.254 -0.2286)
							(mid 0.239121 -0.264521)
							(end 0.2032 -0.2794)
						)
					)
					(width 0)
					(fill yes)
				)
			)
		)
	)
	(footprint ""
		(layer "F.Cu")
		(at 162.179 -41.402 90)
		(property "Reference" "R131"
			(at 0 0 90)
			(layer "F.SilkS")
			(hide yes)
			(effects
				(font
					(size 1.27 1.27)
				)
			)
		)
		(property "Value" "300R2F-GP"
			(at 0.064008 -3.993896 90)
			(unlocked yes)
			(layer "F.Fab")
			(hide yes)
			(effects
				(font
					(size 1.016 1.016)
					(thickness 0.1524)
				)
			)
		)
		(property "Device Type" "R402H16"
			(at 0.064008 -5.517896 90)
			(unlocked yes)
			(layer "F.Fab")
			(hide yes)
			(effects
				(font
					(size 1.016 1.016)
					(thickness 0.1524)
				)
			)
		)
		(duplicate_pad_numbers_are_jumpers no)
		(fp_rect
			(start -0.381 0.8382)
			(end 0.381 -0.8382)
			(stroke
				(width 0)
				(type default)
			)
			(fill no)
			(layer "F.CrtYd")
		)
		(fp_rect
			(start -0.381 0.8382)
			(end 0.381 -0.8382)
			(stroke
				(width 0)
				(type default)
			)
			(fill no)
			(layer "F.Fab")
		)
		(pad "1" smd custom
			(at 0 -0.4318 90)
			(size 0.127 0.127)
			(layers "F.Cu" "F.Mask" "F.Paste")
			(net "C_LED_NSTATUS#")
			(options
				(clearance outline)
				(anchor circle)
			)
			(primitives
				(gr_poly
					(pts
						(arc
							(start -0.2032 -0.2794)
							(mid -0.239121 -0.264521)
							(end -0.254 -0.2286)
						)
						(arc
							(start -0.254 0.2286)
							(mid -0.239121 0.264521)
							(end -0.2032 0.2794)
						)
						(arc
							(start 0.2032 0.2794)
							(mid 0.239121 0.264521)
							(end 0.254 0.2286)
						)
						(arc
							(start 0.254 -0.2286)
							(mid 0.239121 -0.264521)
							(end 0.2032 -0.2794)
						)
					)
					(width 0)
					(fill yes)
				)
			)
		)
		(pad "2" smd custom
			(at 0 0.4318 90)
			(size 0.127 0.127)
			(layers "F.Cu" "F.Mask" "F.Paste")
			(net "P3V3_STBY")
			(options
				(clearance outline)
				(anchor circle)
			)
			(primitives
				(gr_poly
					(pts
						(arc
							(start -0.2032 -0.2794)
							(mid -0.239121 -0.264521)
							(end -0.254 -0.2286)
						)
						(arc
							(start -0.254 0.2286)
							(mid -0.239121 0.264521)
							(end -0.2032 0.2794)
						)
						(arc
							(start 0.2032 0.2794)
							(mid 0.239121 0.264521)
							(end 0.254 0.2286)
						)
						(arc
							(start 0.254 -0.2286)
							(mid 0.239121 -0.264521)
							(end 0.2032 -0.2794)
						)
					)
					(width 0)
					(fill yes)
				)
			)
		)
	)
	(footprint ""
		(layer "F.Cu")
		(at 197.612 -32.6644 90)
		(property "Reference" "PR110"
			(at 0 0 90)
			(layer "F.SilkS")
			(hide yes)
			(effects
				(font
					(size 1.27 1.27)
				)
			)
		)
		(property "Value" "10KR2F-2-GP"
			(at 1.7907 -1.1176 90)
			(unlocked yes)
			(layer "F.Fab")
			(hide yes)
			(effects
				(font
					(size 1.016 1.016)
					(thickness 0.1524)
				)
			)
		)
		(property "Device Type" "R402H16"
			(at 1.7907 -2.6416 90)
			(unlocked yes)
			(layer "F.Fab")
			(hide yes)
			(effects
				(font
					(size 1.016 1.016)
					(thickness 0.1524)
				)
			)
		)
		(duplicate_pad_numbers_are_jumpers no)
		(fp_rect
			(start -0.381 0.8382)
			(end 0.381 -0.8382)
			(stroke
				(width 0)
				(type default)
			)
			(fill no)
			(layer "F.CrtYd")
		)
		(fp_rect
			(start -0.381 0.8382)
			(end 0.381 -0.8382)
			(stroke
				(width 0)
				(type default)
			)
			(fill no)
			(layer "F.Fab")
		)
		(pad "1" smd custom
			(at 0 -0.4318 90)
			(size 0.127 0.127)
			(layers "F.Cu" "F.Mask" "F.Paste")
			(net "VR_PVDDR_A_PHASE1")
			(options
				(clearance outline)
				(anchor circle)
			)
			(primitives
				(gr_poly
					(pts
						(arc
							(start -0.2032 -0.2794)
							(mid -0.239121 -0.264521)
							(end -0.254 -0.2286)
						)
						(arc
							(start -0.254 0.2286)
							(mid -0.239121 0.264521)
							(end -0.2032 0.2794)
						)
						(arc
							(start 0.2032 0.2794)
							(mid 0.239121 0.264521)
							(end 0.254 0.2286)
						)
						(arc
							(start 0.254 -0.2286)
							(mid 0.239121 -0.264521)
							(end 0.2032 -0.2794)
						)
					)
					(width 0)
					(fill yes)
				)
			)
		)
		(pad "2" smd custom
			(at 0 0.4318 90)
			(size 0.127 0.127)
			(layers "F.Cu" "F.Mask" "F.Paste")
			(net "VR_PVDDR_A_GH1_R")
			(options
				(clearance outline)
				(anchor circle)
			)
			(primitives
				(gr_poly
					(pts
						(arc
							(start -0.2032 -0.2794)
							(mid -0.239121 -0.264521)
							(end -0.254 -0.2286)
						)
						(arc
							(start -0.254 0.2286)
							(mid -0.239121 0.264521)
							(end -0.2032 0.2794)
						)
						(arc
							(start 0.2032 0.2794)
							(mid 0.239121 0.264521)
							(end 0.254 0.2286)
						)
						(arc
							(start 0.254 -0.2286)
							(mid 0.239121 -0.264521)
							(end 0.2032 -0.2794)
						)
					)
					(width 0)
					(fill yes)
				)
			)
		)
	)
	(footprint ""
		(layer "F.Cu")
		(at 181.102 -38.1 90)
		(property "Reference" "PR130"
			(at 0 0 90)
			(layer "F.SilkS")
			(hide yes)
			(effects
				(font
					(size 1.27 1.27)
				)
			)
		)
		(property "Value" "0R2J-2-GP"
			(at 0.064008 -3.993896 90)
			(unlocked yes)
			(layer "F.Fab")
			(hide yes)
			(effects
				(font
					(size 1.016 1.016)
					(thickness 0.1524)
				)
			)
		)
		(property "Device Type" "R402H16"
			(at 0.064008 -5.517896 90)
			(unlocked yes)
			(layer "F.Fab")
			(hide yes)
			(effects
				(font
					(size 1.016 1.016)
					(thickness 0.1524)
				)
			)
		)
		(duplicate_pad_numbers_are_jumpers no)
		(fp_rect
			(start -0.381 0.8382)
			(end 0.381 -0.8382)
			(stroke
				(width 0)
				(type default)
			)
			(fill no)
			(layer "F.CrtYd")
		)
		(fp_rect
			(start -0.381 0.8382)
			(end 0.381 -0.8382)
			(stroke
				(width 0)
				(type default)
			)
			(fill no)
			(layer "F.Fab")
		)
		(pad "1" smd custom
			(at 0 -0.4318 90)
			(size 0.127 0.127)
			(layers "F.Cu" "F.Mask" "F.Paste")
			(net "P1V0")
			(options
				(clearance outline)
				(anchor circle)
			)
			(primitives
				(gr_poly
					(pts
						(arc
							(start -0.2032 -0.2794)
							(mid -0.239121 -0.264521)
							(end -0.254 -0.2286)
						)
						(arc
							(start -0.254 0.2286)
							(mid -0.239121 0.264521)
							(end -0.2032 0.2794)
						)
						(arc
							(start 0.2032 0.2794)
							(mid 0.239121 0.264521)
							(end 0.254 0.2286)
						)
						(arc
							(start 0.254 -0.2286)
							(mid 0.239121 -0.264521)
							(end 0.2032 -0.2794)
						)
					)
					(width 0)
					(fill yes)
				)
			)
		)
		(pad "2" smd custom
			(at 0 0.4318 90)
			(size 0.127 0.127)
			(layers "F.Cu" "F.Mask" "F.Paste")
			(net "SVID_CPU_ALERT#")
			(options
				(clearance outline)
				(anchor circle)
			)
			(primitives
				(gr_poly
					(pts
						(arc
							(start -0.2032 -0.2794)
							(mid -0.239121 -0.264521)
							(end -0.254 -0.2286)
						)
						(arc
							(start -0.254 0.2286)
							(mid -0.239121 0.264521)
							(end -0.2032 0.2794)
						)
						(arc
							(start 0.2032 0.2794)
							(mid 0.239121 0.264521)
							(end 0.254 0.2286)
						)
						(arc
							(start 0.254 -0.2286)
							(mid 0.239121 -0.264521)
							(end 0.2032 -0.2794)
						)
					)
					(width 0)
					(fill yes)
				)
			)
		)
	)
	(footprint ""
		(layer "F.Cu")
		(at 168.4528 -52.832 -90)
		(property "Reference" "R188"
			(at 0 0 270)
			(layer "F.SilkS")
			(hide yes)
			(effects
				(font
					(size 1.27 1.27)
				)
			)
		)
		(property "Value" "33R2F-3-GP"
			(at 1.7907 -1.1176 270)
			(unlocked yes)
			(layer "F.Fab")
			(hide yes)
			(effects
				(font
					(size 1.016 1.016)
					(thickness 0.1524)
				)
			)
		)
		(property "Device Type" "R402H16"
			(at 1.7907 -2.6416 270)
			(unlocked yes)
			(layer "F.Fab")
			(hide yes)
			(effects
				(font
					(size 1.016 1.016)
					(thickness 0.1524)
				)
			)
		)
		(duplicate_pad_numbers_are_jumpers no)
		(fp_rect
			(start -0.381 0.8382)
			(end 0.381 -0.8382)
			(stroke
				(width 0)
				(type default)
			)
			(fill no)
			(layer "F.CrtYd")
		)
		(fp_rect
			(start -0.381 0.8382)
			(end 0.381 -0.8382)
			(stroke
				(width 0)
				(type default)
			)
			(fill no)
			(layer "F.Fab")
		)
		(pad "1" smd custom
			(at 0 -0.4318 270)
			(size 0.127 0.127)
			(layers "F.Cu" "F.Mask" "F.Paste")
			(net "C_DATA0")
			(options
				(clearance outline)
				(anchor circle)
			)
			(primitives
				(gr_poly
					(pts
						(arc
							(start -0.2032 -0.2794)
							(mid -0.239121 -0.264521)
							(end -0.254 -0.2286)
						)
						(arc
							(start -0.254 0.2286)
							(mid -0.239121 0.264521)
							(end -0.2032 0.2794)
						)
						(arc
							(start 0.2032 0.2794)
							(mid 0.239121 0.264521)
							(end 0.254 0.2286)
						)
						(arc
							(start 0.254 -0.2286)
							(mid 0.239121 -0.264521)
							(end 0.2032 -0.2794)
						)
					)
					(width 0)
					(fill yes)
				)
			)
		)
		(pad "2" smd custom
			(at 0 0.4318 270)
			(size 0.127 0.127)
			(layers "F.Cu" "F.Mask" "F.Paste")
			(net "C_R_DATA0")
			(options
				(clearance outline)
				(anchor circle)
			)
			(primitives
				(gr_poly
					(pts
						(arc
							(start -0.2032 -0.2794)
							(mid -0.239121 -0.264521)
							(end -0.254 -0.2286)
						)
						(arc
							(start -0.254 0.2286)
							(mid -0.239121 0.264521)
							(end -0.2032 0.2794)
						)
						(arc
							(start 0.2032 0.2794)
							(mid 0.239121 0.264521)
							(end 0.254 0.2286)
						)
						(arc
							(start 0.254 -0.2286)
							(mid 0.239121 -0.264521)
							(end 0.2032 -0.2794)
						)
					)
					(width 0)
					(fill yes)
				)
			)
		)
	)
	(footprint ""
		(layer "F.Cu")
		(at 131.445 -56.388 180)
		(property "Reference" "PC49"
			(at 0 0 180)
			(layer "F.SilkS")
			(hide yes)
			(effects
				(font
					(size 1.27 1.27)
				)
			)
		)
		(property "Value" "SC10U6D3V3MX-GP"
			(at 0 -2.8194 180)
			(unlocked yes)
			(layer "F.Fab")
			(hide yes)
			(effects
				(font
					(size 1.016 1.016)
					(thickness 0.1524)
				)
			)
		)
		(property "Device Type" "C603H38"
			(at 0 -4.3434 180)
			(unlocked yes)
			(layer "F.Fab")
			(hide yes)
			(effects
				(font
					(size 1.016 1.016)
					(thickness 0.1524)
				)
			)
		)
		(duplicate_pad_numbers_are_jumpers no)
		(fp_line
			(start -0.4064 0)
			(end 0.4064 0)
			(stroke
				(width 0.2286)
				(type default)
			)
			(layer "F.SilkS")
		)
		(fp_rect
			(start -0.635 1.1811)
			(end 0.635 -1.1811)
			(stroke
				(width 0)
				(type default)
			)
			(fill no)
			(layer "F.CrtYd")
		)
		(fp_rect
			(start -0.635 1.1811)
			(end 0.635 -1.1811)
			(stroke
				(width 0)
				(type default)
			)
			(fill no)
			(layer "F.Fab")
		)
		(pad "1" smd custom
			(at 0 -0.6604 180)
			(size 0.19685 0.19685)
			(layers "F.Cu" "F.Mask" "F.Paste")
			(net "GND")
			(options
				(clearance outline)
				(anchor circle)
			)
			(primitives
				(gr_poly
					(pts
						(arc
							(start 0.508 -0.2921)
							(mid 0.478242 -0.363942)
							(end 0.4064 -0.3937)
						)
						(arc
							(start -0.4064 -0.3937)
							(mid -0.478242 -0.363942)
							(end -0.508 -0.2921)
						)
						(arc
							(start -0.508 0.2921)
							(mid -0.478242 0.363942)
							(end -0.4064 0.3937)
						)
						(arc
							(start 0.4064 0.3937)
							(mid 0.478242 0.363942)
							(end 0.508 0.2921)
						)
					)
					(width 0)
					(fill yes)
				)
			)
		)
		(pad "2" smd custom
			(at 0 0.6604 180)
			(size 0.19685 0.19685)
			(layers "F.Cu" "F.Mask" "F.Paste")
			(net "PV_VTT_DDR_A")
			(options
				(clearance outline)
				(anchor circle)
			)
			(primitives
				(gr_poly
					(pts
						(arc
							(start 0.508 -0.2921)
							(mid 0.478242 -0.363942)
							(end 0.4064 -0.3937)
						)
						(arc
							(start -0.4064 -0.3937)
							(mid -0.478242 -0.363942)
							(end -0.508 -0.2921)
						)
						(arc
							(start -0.508 0.2921)
							(mid -0.478242 0.363942)
							(end -0.4064 0.3937)
						)
						(arc
							(start 0.4064 0.3937)
							(mid 0.478242 0.363942)
							(end 0.508 0.2921)
						)
					)
					(width 0)
					(fill yes)
				)
			)
		)
	)
)
